# S9S_MB_2U (Grand Teton) — schematic netlist excerpt (pin names and nets, part order shuffled) for the footprints in the layout excerpt that follows; sources: Cadence DE-HDL packaged netlist, KiCad conversion of 03242023_DA0F0TMBIJ0_F0T_Motherboard_J_brd_V01_OCP.brd

R33  Q_RES  196K 1% CHIP  pkg 0402LF  page 89 : A = PD_CHD_CPU0_DIMM2_SAA ; B = GND
R1656  Q_RES  33.2 1% CHIP  pkg 0402LF  page 183 : A = IRQ_SML1_PMBUS_ALERT_N ; B = IRQ_SML1_PMBUS_PLD_ALERT_N

(kicad_pcb
	(version 20260206)
	(generator "pcbnew")
	(generator_version "10.0")
	(general
		(thickness 1.6)
		(legacy_teardrops no)
	)
	(paper "A4")
	(title_block
		(title "03242023_DA0F0TMBIJ0_F0T_Motherboard_J_brd_V01_OCP.brd")
		(comment 1 "Grand Teton / footprints 5345-5346 of 6105")
	)
	(layers
		(0 "F.Cu" signal "TOP")
		(4 "In1.Cu" signal "GND")
		(6 "In2.Cu" signal "IN1")
		(8 "In3.Cu" signal "GND1")
		(10 "In4.Cu" signal "IN2")
		(12 "In5.Cu" signal "GND2")
		(14 "In6.Cu" signal "IN3")
		(16 "In7.Cu" signal "GND3")
		(18 "In8.Cu" signal "VCC")
		(20 "In9.Cu" signal "VCC1")
		(22 "In10.Cu" signal "GND4")
		(24 "In11.Cu" signal "IN4")
		(26 "In12.Cu" signal "GND5")
		(28 "In13.Cu" signal "IN5")
		(30 "In14.Cu" signal "GND6")
		(32 "In15.Cu" signal "IN6")
		(34 "In16.Cu" signal "GND7")
		(2 "B.Cu" signal "BOTTOM")
		(9 "F.Adhes" user "F.Adhesive")
		(11 "B.Adhes" user "B.Adhesive")
		(13 "F.Paste" user "Package Geometry/Pastemask Top")
		(15 "B.Paste" user "Package Geometry/Pastemask Bottom")
		(5 "F.SilkS" user "Ref Des/Silkscreen Top")
		(7 "B.SilkS" user "Ref Des/Silkscreen Bottom")
		(1 "F.Mask" user "Board Geometry/Soldermask Top")
		(3 "B.Mask" user "Board Geometry/Soldermask Bottom")
		(17 "Dwgs.User" user "User.Drawings")
		(19 "Cmts.User" user "User.Comments")
		(21 "Eco1.User" user "User.Eco1")
		(23 "Eco2.User" user "User.Eco2")
		(25 "Edge.Cuts" user "Board Geometry/Outline")
		(27 "Margin" user)
		(31 "F.CrtYd" user "Package Geometry/Place Bound Top")
		(29 "B.CrtYd" user "Package Geometry/Place Bound Bottom")
		(35 "F.Fab" user "Ref Des/Assembly Top")
		(33 "B.Fab" user "Ref Des/Assembly Bottom")
	)
	(footprint ""
		(layer "B.Cu")
		(at 265.406378 -318.697102)
		(property "Reference" "R33"
			(at 0 0 0)
			(layer "B.SilkS")
			(hide yes)
			(effects
				(font
					(size 1.27 1.27)
				)
				(justify mirror)
			)
		)
		(property "Value" ""
			(at 0 0 0)
			(layer "B.Fab")
			(effects
				(font
					(size 1.27 1.27)
				)
				(justify mirror)
			)
		)
		(duplicate_pad_numbers_are_jumpers no)
		(fp_line
			(start -0.7874 -0.4064)
			(end -0.7874 0.4064)
			(stroke
				(width 0.1524)
				(type default)
			)
			(layer "B.SilkS")
		)
		(fp_line
			(start -0.7874 0.4064)
			(end 0.7874 0.4064)
			(stroke
				(width 0.1524)
				(type default)
			)
			(layer "B.SilkS")
		)
		(fp_line
			(start 0.7874 -0.4064)
			(end -0.7874 -0.4064)
			(stroke
				(width 0.1524)
				(type default)
			)
			(layer "B.SilkS")
		)
		(fp_line
			(start 0.7874 0.4064)
			(end 0.7874 -0.4064)
			(stroke
				(width 0.1524)
				(type default)
			)
			(layer "B.SilkS")
		)
		(fp_line
			(start -0.67945 -0.3048)
			(end -0.67945 0.3048)
			(stroke
				(width 0.1)
				(type default)
			)
			(layer "B.Fab")
		)
		(fp_line
			(start -0.67945 0.3048)
			(end -0.120396 0.3048)
			(stroke
				(width 0.1)
				(type default)
			)
			(layer "B.Fab")
		)
		(fp_line
			(start -0.12065 -0.3048)
			(end -0.67945 -0.3048)
			(stroke
				(width 0.1)
				(type default)
			)
			(layer "B.Fab")
		)
		(fp_line
			(start -0.12065 -0.2794)
			(end -0.12065 -0.3048)
			(stroke
				(width 0.1)
				(type default)
			)
			(layer "B.Fab")
		)
		(fp_line
			(start -0.120396 0.2794)
			(end 0.12065 0.2794)
			(stroke
				(width 0.1)
				(type default)
			)
			(layer "B.Fab")
		)
		(fp_line
			(start -0.120396 0.3048)
			(end -0.120396 0.2794)
			(stroke
				(width 0.1)
				(type default)
			)
			(layer "B.Fab")
		)
		(fp_line
			(start 0.12065 -0.305054)
			(end 0.12065 -0.2794)
			(stroke
				(width 0.1)
				(type default)
			)
			(layer "B.Fab")
		)
		(fp_line
			(start 0.12065 -0.2794)
			(end -0.12065 -0.2794)
			(stroke
				(width 0.1)
				(type default)
			)
			(layer "B.Fab")
		)
		(fp_line
			(start 0.12065 0.2794)
			(end 0.12065 0.3048)
			(stroke
				(width 0.1)
				(type default)
			)
			(layer "B.Fab")
		)
		(fp_line
			(start 0.12065 0.3048)
			(end 0.67945 0.3048)
			(stroke
				(width 0.1)
				(type default)
			)
			(layer "B.Fab")
		)
		(fp_line
			(start 0.67945 -0.305054)
			(end 0.12065 -0.305054)
			(stroke
				(width 0.1)
				(type default)
			)
			(layer "B.Fab")
		)
		(fp_line
			(start 0.67945 0.3048)
			(end 0.67945 -0.305054)
			(stroke
				(width 0.1)
				(type default)
			)
			(layer "B.Fab")
		)
		(pad "1" smd circle
			(at 0.40005 0 180)
			(size 0 0)
			(layers "B.Cu" "B.Mask" "B.Paste")
			(net "PD_CHD_CPU0_DIMM2_SAA")
		)
		(pad "2" smd circle
			(at -0.40005 0 180)
			(size 0 0)
			(layers "B.Cu" "B.Mask" "B.Paste")
			(net "GND")
		)
	)
	(footprint ""
		(layer "B.Cu")
		(at 312.443622 -36.820348)
		(property "Reference" "R1656"
			(at 0 0 0)
			(layer "B.SilkS")
			(hide yes)
			(effects
				(font
					(size 1.27 1.27)
				)
				(justify mirror)
			)
		)
		(property "Value" ""
			(at 0 0 0)
			(layer "B.Fab")
			(effects
				(font
					(size 1.27 1.27)
				)
				(justify mirror)
			)
		)
		(duplicate_pad_numbers_are_jumpers no)
		(fp_line
			(start -0.7874 -0.4064)
			(end -0.7874 0.4064)
			(stroke
				(width 0.1524)
				(type default)
			)
			(layer "B.SilkS")
		)
		(fp_line
			(start -0.7874 0.4064)
			(end 0.7874 0.4064)
			(stroke
				(width 0.1524)
				(type default)
			)
			(layer "B.SilkS")
		)
		(fp_line
			(start 0.7874 -0.4064)
			(end -0.7874 -0.4064)
			(stroke
				(width 0.1524)
				(type default)
			)
			(layer "B.SilkS")
		)
		(fp_line
			(start 0.7874 0.4064)
			(end 0.7874 -0.4064)
			(stroke
				(width 0.1524)
				(type default)
			)
			(layer "B.SilkS")
		)
		(fp_line
			(start -0.67945 -0.3048)
			(end -0.67945 0.3048)
			(stroke
				(width 0.1)
				(type default)
			)
			(layer "B.Fab")
		)
		(fp_line
			(start -0.67945 0.3048)
			(end -0.120396 0.3048)
			(stroke
				(width 0.1)
				(type default)
			)
			(layer "B.Fab")
		)
		(fp_line
			(start -0.12065 -0.3048)
			(end -0.67945 -0.3048)
			(stroke
				(width 0.1)
				(type default)
			)
			(layer "B.Fab")
		)
		(fp_line
			(start -0.12065 -0.2794)
			(end -0.12065 -0.3048)
			(stroke
				(width 0.1)
				(type default)
			)
			(layer "B.Fab")
		)
		(fp_line
			(start -0.120396 0.2794)
			(end 0.12065 0.2794)
			(stroke
				(width 0.1)
				(type default)
			)
			(layer "B.Fab")
		)
		(fp_line
			(start -0.120396 0.3048)
			(end -0.120396 0.2794)
			(stroke
				(width 0.1)
				(type default)
			)
			(layer "B.Fab")
		)
		(fp_line
			(start 0.12065 -0.305054)
			(end 0.12065 -0.2794)
			(stroke
				(width 0.1)
				(type default)
			)
			(layer "B.Fab")
		)
		(fp_line
			(start 0.12065 -0.2794)
			(end -0.12065 -0.2794)
			(stroke
				(width 0.1)
				(type default)
			)
			(layer "B.Fab")
		)
		(fp_line
			(start 0.12065 0.2794)
			(end 0.12065 0.3048)
			(stroke
				(width 0.1)
				(type default)
			)
			(layer "B.Fab")
		)
		(fp_line
			(start 0.12065 0.3048)
			(end 0.67945 0.3048)
			(stroke
				(width 0.1)
				(type default)
			)
			(layer "B.Fab")
		)
		(fp_line
			(start 0.67945 -0.305054)
			(end 0.12065 -0.305054)
			(stroke
				(width 0.1)
				(type default)
			)
			(layer "B.Fab")
		)
		(fp_line
			(start 0.67945 0.3048)
			(end 0.67945 -0.305054)
			(stroke
				(width 0.1)
				(type default)
			)
			(layer "B.Fab")
		)
		(pad "1" smd circle
			(at 0.40005 0 180)
			(size 0 0)
			(layers "B.Cu" "B.Mask" "B.Paste")
			(net "IRQ_SML1_PMBUS_ALERT_N")
		)
		(pad "2" smd circle
			(at -0.40005 0 180)
			(size 0 0)
			(layers "B.Cu" "B.Mask" "B.Paste")
			(net "IRQ_SML1_PMBUS_PLD_ALERT_N")
		)
	)
)
